# T6G (Grand Teton) — schematic netlist excerpt (pin names and nets, part order shuffled) for the footprints in the layout excerpt that follows; sources: Cadence DE-HDL packaged netlist, KiCad conversion of 04192023_DAF0TMB3IC0_F0TG_MB_C_brd_V02_OCP.brd

R1587  Q_RES  49.9 1% CHIP  pkg 0402LF  page 105 : A = I3C_SPD_DDRGL_CPU1_SCL ; B = I3C_SPD_DDRH_CPU1_SCL
C2496  Q_CAP  22UF 4V 20% X6S  pkg C0402  page 74 : A = PVDD11_S3_P1 ; B = GND

(kicad_pcb
	(version 20260206)
	(generator "pcbnew")
	(generator_version "10.0")
	(general
		(thickness 1.6)
		(legacy_teardrops no)
	)
	(paper "A4")
	(title_block
		(title "04192023_DAF0TMB3IC0_F0TG_MB_C_brd_V02_OCP.brd")
		(comment 1 "Grand Teton / footprints 5837-5838 of 8354")
	)
	(layers
		(0 "F.Cu" signal "TOP")
		(4 "In1.Cu" signal "GND")
		(6 "In2.Cu" signal "IN1")
		(8 "In3.Cu" signal "GND1")
		(10 "In4.Cu" signal "IN2")
		(12 "In5.Cu" signal "GND2")
		(14 "In6.Cu" signal "IN3")
		(16 "In7.Cu" signal "GND3")
		(18 "In8.Cu" signal "VCC")
		(20 "In9.Cu" signal "VCC1")
		(22 "In10.Cu" signal "GND4")
		(24 "In11.Cu" signal "IN4")
		(26 "In12.Cu" signal "GND5")
		(28 "In13.Cu" signal "IN5")
		(30 "In14.Cu" signal "GND6")
		(32 "In15.Cu" signal "IN6")
		(34 "In16.Cu" signal "GND7")
		(2 "B.Cu" signal "BOTTOM")
		(9 "F.Adhes" user "F.Adhesive")
		(11 "B.Adhes" user "B.Adhesive")
		(13 "F.Paste" user "Package Geometry/Pastemask Top")
		(15 "B.Paste" user "Package Geometry/Pastemask Bottom")
		(5 "F.SilkS" user "Ref Des/Silkscreen Top")
		(7 "B.SilkS" user "Ref Des/Silkscreen Bottom")
		(1 "F.Mask" user "Board Geometry/Soldermask Top")
		(3 "B.Mask" user "Board Geometry/Soldermask Bottom")
		(17 "Dwgs.User" user "User.Drawings")
		(19 "Cmts.User" user "User.Comments")
		(21 "Eco1.User" user "User.Eco1")
		(23 "Eco2.User" user "User.Eco2")
		(25 "Edge.Cuts" user "Board Geometry/Outline")
		(27 "Margin" user)
		(31 "F.CrtYd" user "Package Geometry/Place Bound Top")
		(29 "B.CrtYd" user "Package Geometry/Place Bound Bottom")
		(35 "F.Fab" user "Ref Des/Assembly Top")
		(33 "B.Fab" user "Ref Des/Assembly Bottom")
	)
	(footprint ""
		(layer "B.Cu")
		(at 115.864386 -264.354564)
		(property "Reference" "C2496"
			(at 0 0 0)
			(layer "B.SilkS")
			(hide yes)
			(effects
				(font
					(size 1.27 1.27)
				)
				(justify mirror)
			)
		)
		(property "Value" ""
			(at 0 0 0)
			(layer "B.Fab")
			(effects
				(font
					(size 1.27 1.27)
				)
				(justify mirror)
			)
		)
		(duplicate_pad_numbers_are_jumpers no)
		(fp_line
			(start -0.7874 -0.4064)
			(end -0.7874 0.4064)
			(stroke
				(width 0.1524)
				(type default)
			)
			(layer "B.SilkS")
		)
		(fp_line
			(start -0.7874 0.4064)
			(end 0.7874 0.4064)
			(stroke
				(width 0.1524)
				(type default)
			)
			(layer "B.SilkS")
		)
		(fp_line
			(start 0.7874 -0.4064)
			(end -0.7874 -0.4064)
			(stroke
				(width 0.1524)
				(type default)
			)
			(layer "B.SilkS")
		)
		(fp_line
			(start 0.7874 0.4064)
			(end 0.7874 -0.4064)
			(stroke
				(width 0.1524)
				(type default)
			)
			(layer "B.SilkS")
		)
		(fp_line
			(start -0.67945 -0.3048)
			(end -0.67945 0.3048)
			(stroke
				(width 0.1)
				(type default)
			)
			(layer "B.Fab")
		)
		(fp_line
			(start -0.67945 0.3048)
			(end -0.120396 0.3048)
			(stroke
				(width 0.1)
				(type default)
			)
			(layer "B.Fab")
		)
		(fp_line
			(start -0.12065 -0.3048)
			(end -0.67945 -0.3048)
			(stroke
				(width 0.1)
				(type default)
			)
			(layer "B.Fab")
		)
		(fp_line
			(start -0.12065 -0.2794)
			(end -0.12065 -0.3048)
			(stroke
				(width 0.1)
				(type default)
			)
			(layer "B.Fab")
		)
		(fp_line
			(start -0.120396 0.2794)
			(end 0.12065 0.2794)
			(stroke
				(width 0.1)
				(type default)
			)
			(layer "B.Fab")
		)
		(fp_line
			(start -0.120396 0.3048)
			(end -0.120396 0.2794)
			(stroke
				(width 0.1)
				(type default)
			)
			(layer "B.Fab")
		)
		(fp_line
			(start 0.12065 -0.305054)
			(end 0.12065 -0.2794)
			(stroke
				(width 0.1)
				(type default)
			)
			(layer "B.Fab")
		)
		(fp_line
			(start 0.12065 -0.2794)
			(end -0.12065 -0.2794)
			(stroke
				(width 0.1)
				(type default)
			)
			(layer "B.Fab")
		)
		(fp_line
			(start 0.12065 0.2794)
			(end 0.12065 0.3048)
			(stroke
				(width 0.1)
				(type default)
			)
			(layer "B.Fab")
		)
		(fp_line
			(start 0.12065 0.3048)
			(end 0.67945 0.3048)
			(stroke
				(width 0.1)
				(type default)
			)
			(layer "B.Fab")
		)
		(fp_line
			(start 0.67945 -0.305054)
			(end 0.12065 -0.305054)
			(stroke
				(width 0.1)
				(type default)
			)
			(layer "B.Fab")
		)
		(fp_line
			(start 0.67945 0.3048)
			(end 0.67945 -0.305054)
			(stroke
				(width 0.1)
				(type default)
			)
			(layer "B.Fab")
		)
		(pad "1" smd circle
			(at 0.40005 0 180)
			(size 0 0)
			(layers "B.Cu" "B.Mask" "B.Paste")
			(net "PVDD11_S3_P1")
		)
		(pad "2" smd circle
			(at -0.40005 0 180)
			(size 0 0)
			(layers "B.Cu" "B.Mask" "B.Paste")
			(net "GND")
		)
	)
	(footprint ""
		(layer "B.Cu")
		(at 175.316642 -194.8942 180)
		(property "Reference" "R1587"
			(at 0 0 0)
			(layer "B.SilkS")
			(hide yes)
			(effects
				(font
					(size 1.27 1.27)
				)
				(justify mirror)
			)
		)
		(property "Value" ""
			(at 0 0 0)
			(layer "B.Fab")
			(effects
				(font
					(size 1.27 1.27)
				)
				(justify mirror)
			)
		)
		(duplicate_pad_numbers_are_jumpers no)
		(fp_line
			(start 0.7874 0.4064)
			(end 0.7874 -0.4064)
			(stroke
				(width 0.1524)
				(type default)
			)
			(layer "B.SilkS")
		)
		(fp_line
			(start 0.7874 -0.4064)
			(end -0.7874 -0.4064)
			(stroke
				(width 0.1524)
				(type default)
			)
			(layer "B.SilkS")
		)
		(fp_line
			(start -0.7874 0.4064)
			(end 0.7874 0.4064)
			(stroke
				(width 0.1524)
				(type default)
			)
			(layer "B.SilkS")
		)
		(fp_line
			(start -0.7874 -0.4064)
			(end -0.7874 0.4064)
			(stroke
				(width 0.1524)
				(type default)
			)
			(layer "B.SilkS")
		)
		(fp_line
			(start 0.67945 0.3048)
			(end 0.67945 -0.305054)
			(stroke
				(width 0.1)
				(type default)
			)
			(layer "B.Fab")
		)
		(fp_line
			(start 0.67945 -0.305054)
			(end 0.12065 -0.305054)
			(stroke
				(width 0.1)
				(type default)
			)
			(layer "B.Fab")
		)
		(fp_line
			(start 0.12065 0.3048)
			(end 0.67945 0.3048)
			(stroke
				(width 0.1)
				(type default)
			)
			(layer "B.Fab")
		)
		(fp_line
			(start 0.12065 0.2794)
			(end 0.12065 0.3048)
			(stroke
				(width 0.1)
				(type default)
			)
			(layer "B.Fab")
		)
		(fp_line
			(start 0.12065 -0.2794)
			(end -0.12065 -0.2794)
			(stroke
				(width 0.1)
				(type default)
			)
			(layer "B.Fab")
		)
		(fp_line
			(start 0.12065 -0.305054)
			(end 0.12065 -0.2794)
			(stroke
				(width 0.1)
				(type default)
			)
			(layer "B.Fab")
		)
		(fp_line
			(start -0.120396 0.3048)
			(end -0.120396 0.2794)
			(stroke
				(width 0.1)
				(type default)
			)
			(layer "B.Fab")
		)
		(fp_line
			(start -0.120396 0.2794)
			(end 0.12065 0.2794)
			(stroke
				(width 0.1)
				(type default)
			)
			(layer "B.Fab")
		)
		(fp_line
			(start -0.12065 -0.2794)
			(end -0.12065 -0.3048)
			(stroke
				(width 0.1)
				(type default)
			)
			(layer "B.Fab")
		)
		(fp_line
			(start -0.12065 -0.3048)
			(end -0.67945 -0.3048)
			(stroke
				(width 0.1)
				(type default)
			)
			(layer "B.Fab")
		)
		(fp_line
			(start -0.67945 0.3048)
			(end -0.120396 0.3048)
			(stroke
				(width 0.1)
				(type default)
			)
			(layer "B.Fab")
		)
		(fp_line
			(start -0.67945 -0.3048)
			(end -0.67945 0.3048)
			(stroke
				(width 0.1)
				(type default)
			)
			(layer "B.Fab")
		)
		(pad "1" smd circle
			(at 0.40005 0)
			(size 0 0)
			(layers "B.Cu" "B.Mask" "B.Paste")
			(net "I3C_SPD_DDRGL_CPU1_SCL")
		)
		(pad "2" smd circle
			(at -0.40005 0)
			(size 0 0)
			(layers "B.Cu" "B.Mask" "B.Paste")
			(net "I3C_SPD_DDRH_CPU1_SCL")
		)
	)
)
